(kicad_pcb
	(version 20221018)
	(generator pcbnew)
	(general
    (thickness 1.562)
  )
	(paper "A4")
	(title_block
    (title "Thunderbolt PCIe Adaper")
    (date "2024-07-09")
    (rev "1.0.3")
    (comment 1 "www.antmicro.com")
    (comment 2 "Antmicro Ltd.")
		(comment 9 "footprints 219-227 of 271")
	)
	(layers
    (0 "F.Cu" signal)
    (1 "In1.Cu" signal)
    (2 "In2.Cu" signal)
    (3 "In3.Cu" signal)
    (4 "In4.Cu" signal)
    (31 "B.Cu" signal)
    (32 "B.Adhes" user "B.Adhesive")
    (33 "F.Adhes" user "F.Adhesive")
    (34 "B.Paste" user)
    (35 "F.Paste" user)
    (36 "B.SilkS" user "B.Silkscreen")
    (37 "F.SilkS" user "F.Silkscreen")
    (38 "B.Mask" user)
    (39 "F.Mask" user)
    (40 "Dwgs.User" user "User.Drawings")
    (41 "Cmts.User" user "User.Comments")
    (42 "Eco1.User" user "User.Eco1")
    (43 "Eco2.User" user "User.Eco2")
    (44 "Edge.Cuts" user)
    (45 "Margin" user)
    (46 "B.CrtYd" user "B.Courtyard")
    (47 "F.CrtYd" user "F.Courtyard")
    (48 "B.Fab" user)
    (49 "F.Fab" user)
  )
	(footprint "antmicro-footprints:R_0402_1005Metric" (layer "B.Cu")
    (at 156.89 57.39 -90)
    (descr "Resistor SMD 0402")
    (tags "resistor SMD 0402")
    (property "Author" "Antmicro")
    (property "License" "Apache-2.0")
    (property "MPN" "CR0402-FX-3301GLF")
    (property "Manufacturer" "Bourns")
    (property "Sheetfile" "power.kicad_sch")
    (property "Sheetname" "Power")
    (property "Tolerance" "1%")
    (property "Val" "3k3")
    (property "ki_description" "SMD Chip Resistor, 3.3 kohm, ± 1%, 63 mW, 0402 [1005 Metric], Thick Film, General Purpose")
    (property "ki_keywords" "0402, SMT, RESISTOR, PASSIVE")
    (attr smd)
    (fp_text reference "R14" (at -3.034 -0.479 90) (layer "B.SilkS")
        (effects (font (size 0.7 0.7) (thickness 0.15)) (justify left bottom mirror))
    )
    (fp_text value "R_3k3_0402" (at -1.011843 -1.772047 90) (layer "B.Fab")
        (effects (font (size 0.7 0.7) (thickness 0.15)) (justify left bottom mirror))
    )
    (fp_text user "License: Apache-2.0" (at -0.95 -5.169 90) (layer "B.Fab") hide
        (effects (font (size 0.7 0.7) (thickness 0.15)) (justify left bottom mirror))
    )
    (fp_text user "${REFERENCE}" (at -0.95 -3.168 90) (layer "B.Fab") hide
        (effects (font (size 0.7 0.7) (thickness 0.15)) (justify left bottom mirror))
    )
    (fp_text user "Author: Antmicro" (at -0.95 -4.169 90) (layer "B.Fab") hide
        (effects (font (size 0.7 0.7) (thickness 0.15)) (justify left bottom mirror))
    )
    (fp_rect (start -0.925 0.47) (end 0.925 -0.47)
      (stroke (width 0.05) (type default)) (fill none) (layer "B.CrtYd"))
    (fp_rect (start -0.5 0.25) (end 0.5 -0.25)
      (stroke (width 0.15) (type solid)) (fill none) (layer "B.Fab"))
    (pad "1" smd roundrect (at -0.48 0 270) (size 0.59 0.64) (layers "B.Cu" "B.Paste" "B.Mask") (roundrect_rratio 0.25)
      (net 9 "/Power/TPS_3V3") (pintype "passive"))
    (pad "2" smd roundrect (at 0.48 0 270) (size 0.59 0.64) (layers "B.Cu" "B.Paste" "B.Mask") (roundrect_rratio 0.25)
      (net 149 "Net-(U3-I2C_SDA2)") (pintype "passive"))
  )
	(footprint "antmicro-footprints:R_0402_1005Metric" (layer "B.Cu")
    (at 156.91 59.47 90)
    (descr "Resistor SMD 0402")
    (tags "resistor SMD 0402")
    (property "Author" "Antmicro")
    (property "License" "Apache-2.0")
    (property "MPN" "CR0402-FX-1003GLF")
    (property "Manufacturer" "Bourns")
    (property "Sheetfile" "power.kicad_sch")
    (property "Sheetname" "Power")
    (property "Tolerance" "1%")
    (property "Val" "100k")
    (property "ki_description" "SMD Chip Resistor, 100 kohm, ± 1%, 62.5 mW, 0402 [1005 Metric], Thick Film, General Purpose")
    (property "ki_keywords" "0402, SMT, RESISTOR, PASSIVE")
    (attr smd)
    (fp_text reference "R33" (at 4.86 -5.526 270) (layer "B.SilkS")
        (effects (font (size 0.7 0.7) (thickness 0.15)) (justify left bottom mirror))
    )
    (fp_text value "R_100k_0402" (at -1.011843 -1.772047 270) (layer "B.Fab")
        (effects (font (size 0.7 0.7) (thickness 0.15)) (justify left bottom mirror))
    )
    (fp_text user "License: Apache-2.0" (at -0.95 -5.169 270) (layer "B.Fab") hide
        (effects (font (size 0.7 0.7) (thickness 0.15)) (justify left bottom mirror))
    )
    (fp_text user "${REFERENCE}" (at -0.95 -3.168 270) (layer "B.Fab") hide
        (effects (font (size 0.7 0.7) (thickness 0.15)) (justify left bottom mirror))
    )
    (fp_text user "Author: Antmicro" (at -0.95 -4.169 270) (layer "B.Fab") hide
        (effects (font (size 0.7 0.7) (thickness 0.15)) (justify left bottom mirror))
    )
    (fp_rect (start -0.925 0.47) (end 0.925 -0.47)
      (stroke (width 0.05) (type default)) (fill none) (layer "B.CrtYd"))
    (fp_rect (start -0.5 0.25) (end 0.5 -0.25)
      (stroke (width 0.15) (type solid)) (fill none) (layer "B.Fab"))
    (pad "1" smd roundrect (at -0.48 0 90) (size 0.59 0.64) (layers "B.Cu" "B.Paste" "B.Mask") (roundrect_rratio 0.25)
      (net 166 "Net-(U3-HRESET)") (pintype "passive"))
    (pad "2" smd roundrect (at 0.48 0 90) (size 0.59 0.64) (layers "B.Cu" "B.Paste" "B.Mask") (roundrect_rratio 0.25)
      (net 1 "GND") (pintype "passive"))
  )
	(footprint "antmicro-footprints:C_0402_1005Metric" (layer "B.Cu")
    (at 155.085 77.42 180)
    (descr "Capacitor SMD 0402")
    (tags "capacitor SMD 0402")
    (property "Author" "Antmicro")
    (property "Dielectric" "")
    (property "License" "Apache-2.0")
    (property "MPN" "CC0402KRX5R6BB224")
    (property "Manufacturer" "YAGEO")
    (property "Sheetfile" "tb.kicad_sch")
    (property "Sheetname" "TB Controller")
    (property "Val" "220n")
    (property "Voltage" "")
    (property "ki_description" "SMD Multilayer Ceramic Capacitor, 0.22 µF, 10 V, 0402 [1005 Metric], ± 10%, X5R, CC Series")
    (property "ki_keywords" "0402, SMT, CAPACITOR, PASSIVE, MLCC, CERAMIC")
    (attr smd)
    (fp_text reference "C100" (at 1.034 -0.431) (layer "B.SilkS")
        (effects (font (size 0.7 0.7) (thickness 0.15)) (justify left bottom mirror))
    )
    (fp_text value "C_220n_0402" (at -1.022927 -2.155213) (layer "B.Fab")
        (effects (font (size 0.7 0.7) (thickness 0.15)) (justify left bottom mirror))
    )
    (fp_text user "Author: Antmicro" (at -0.939 -3.399) (layer "B.Fab") hide
        (effects (font (size 0.7 0.7) (thickness 0.15)) (justify left bottom mirror))
    )
    (fp_text user "${REFERENCE}" (at -0.939 -4.599) (layer "B.Fab") hide
        (effects (font (size 0.7 0.7) (thickness 0.15)) (justify left bottom mirror))
    )
    (fp_text user "License: Apache-2.0" (at -0.939 -5.799) (layer "B.Fab") hide
        (effects (font (size 0.7 0.7) (thickness 0.15)) (justify left bottom mirror))
    )
    (fp_rect (start -0.925 0.47) (end 0.925 -0.47)
      (stroke (width 0.05) (type default)) (fill none) (layer "B.CrtYd"))
    (fp_line (start -0.494 -0.248) (end -0.494 0.25)
      (stroke (width 0.15) (type solid)) (layer "B.Fab"))
    (fp_line (start -0.494 0.25) (end 0.504 0.25)
      (stroke (width 0.15) (type solid)) (layer "B.Fab"))
    (fp_line (start 0.504 -0.248) (end -0.494 -0.248)
      (stroke (width 0.15) (type solid)) (layer "B.Fab"))
    (fp_line (start 0.504 0.25) (end 0.504 -0.248)
      (stroke (width 0.15) (type solid)) (layer "B.Fab"))
    (pad "1" smd roundrect (at -0.48 0 180) (size 0.59 0.64) (layers "B.Cu" "B.Paste" "B.Mask") (roundrect_rratio 0.25)
      (net 14 "TB_TX1_P") (pintype "passive"))
    (pad "2" smd roundrect (at 0.48 0 180) (size 0.59 0.64) (layers "B.Cu" "B.Paste" "B.Mask") (roundrect_rratio 0.25)
      (net 15 "/TB Controller/PA_TX1_P") (pintype "passive"))
  )
	(footprint "antmicro-footprints:R_0402_1005Metric" (layer "B.Cu")
    (at 130.05 68.77 90)
    (descr "Resistor SMD 0402")
    (tags "resistor SMD 0402")
    (property "Author" "Antmicro")
    (property "License" "Apache-2.0")
    (property "MPN" "CR0402-FX-1004GLF")
    (property "Manufacturer" "Bourns")
    (property "Sheetfile" "tb.kicad_sch")
    (property "Sheetname" "TB Controller")
    (property "Tolerance" "1%")
    (property "Val" "1M")
    (property "ki_description" "SMD Chip Resistor, 1 Mohm, ± 1%, 62.5 mW, 0402 [1005 Metric], Thick Film, General Purpose")
    (property "ki_keywords" "0402, SMT, RESISTOR, PASSIVE")
    (attr smd)
    (fp_text reference "R82" (at 1.079 -2.678 270) (layer "B.SilkS")
        (effects (font (size 0.7 0.7) (thickness 0.15)) (justify left bottom mirror))
    )
    (fp_text value "R_1M_0402" (at -1.011843 -1.772047 270) (layer "B.Fab")
        (effects (font (size 0.7 0.7) (thickness 0.15)) (justify left bottom mirror))
    )
    (fp_text user "License: Apache-2.0" (at -0.95 -5.169 270) (layer "B.Fab") hide
        (effects (font (size 0.7 0.7) (thickness 0.15)) (justify left bottom mirror))
    )
    (fp_text user "${REFERENCE}" (at -0.95 -3.168 270) (layer "B.Fab") hide
        (effects (font (size 0.7 0.7) (thickness 0.15)) (justify left bottom mirror))
    )
    (fp_text user "Author: Antmicro" (at -0.95 -4.169 270) (layer "B.Fab") hide
        (effects (font (size 0.7 0.7) (thickness 0.15)) (justify left bottom mirror))
    )
    (fp_rect (start -0.925 0.47) (end 0.925 -0.47)
      (stroke (width 0.05) (type default)) (fill none) (layer "B.CrtYd"))
    (fp_rect (start -0.5 0.25) (end 0.5 -0.25)
      (stroke (width 0.15) (type solid)) (fill none) (layer "B.Fab"))
    (pad "1" smd roundrect (at -0.48 0 90) (size 0.59 0.64) (layers "B.Cu" "B.Paste" "B.Mask") (roundrect_rratio 0.25)
      (net 197 "Net-(U4C-GPIO_8)") (pintype "passive"))
    (pad "2" smd roundrect (at 0.48 0 90) (size 0.59 0.64) (layers "B.Cu" "B.Paste" "B.Mask") (roundrect_rratio 0.25)
      (net 1 "GND") (pintype "passive"))
  )
	(footprint "antmicro-footprints:R_0402_1005Metric" (layer "B.Cu")
    (at 155.89 57.39 -90)
    (descr "Resistor SMD 0402")
    (tags "resistor SMD 0402")
    (property "Author" "Antmicro")
    (property "License" "Apache-2.0")
    (property "MPN" "CR0402-FX-3301GLF")
    (property "Manufacturer" "Bourns")
    (property "Sheetfile" "power.kicad_sch")
    (property "Sheetname" "Power")
    (property "Tolerance" "1%")
    (property "Val" "3k3")
    (property "ki_description" "SMD Chip Resistor, 3.3 kohm, ± 1%, 63 mW, 0402 [1005 Metric], Thick Film, General Purpose")
    (property "ki_keywords" "0402, SMT, RESISTOR, PASSIVE")
    (attr smd)
    (fp_text reference "R15" (at -3.034 -0.479 90) (layer "B.SilkS")
        (effects (font (size 0.7 0.7) (thickness 0.15)) (justify left bottom mirror))
    )
    (fp_text value "R_3k3_0402" (at -1.011843 -1.772047 90) (layer "B.Fab")
        (effects (font (size 0.7 0.7) (thickness 0.15)) (justify left bottom mirror))
    )
    (fp_text user "Author: Antmicro" (at -0.95 -4.169 90) (layer "B.Fab") hide
        (effects (font (size 0.7 0.7) (thickness 0.15)) (justify left bottom mirror))
    )
    (fp_text user "${REFERENCE}" (at -0.95 -3.168 90) (layer "B.Fab") hide
        (effects (font (size 0.7 0.7) (thickness 0.15)) (justify left bottom mirror))
    )
    (fp_text user "License: Apache-2.0" (at -0.95 -5.169 90) (layer "B.Fab") hide
        (effects (font (size 0.7 0.7) (thickness 0.15)) (justify left bottom mirror))
    )
    (fp_rect (start -0.925 0.47) (end 0.925 -0.47)
      (stroke (width 0.05) (type default)) (fill none) (layer "B.CrtYd"))
    (fp_rect (start -0.5 0.25) (end 0.5 -0.25)
      (stroke (width 0.15) (type solid)) (fill none) (layer "B.Fab"))
    (pad "1" smd roundrect (at -0.48 0 270) (size 0.59 0.64) (layers "B.Cu" "B.Paste" "B.Mask") (roundrect_rratio 0.25)
      (net 9 "/Power/TPS_3V3") (pintype "passive"))
    (pad "2" smd roundrect (at 0.48 0 270) (size 0.59 0.64) (layers "B.Cu" "B.Paste" "B.Mask") (roundrect_rratio 0.25)
      (net 150 "Net-(U3-I2C_SCL2)") (pintype "passive"))
  )
	(footprint "antmicro-footprints:C_0402_1005Metric" (layer "B.Cu")
    (at 153.41 64.96 180)
    (descr "Capacitor SMD 0402")
    (tags "capacitor SMD 0402")
    (property "Author" "Antmicro")
    (property "Dielectric" "")
    (property "License" "Apache-2.0")
    (property "MPN" "C1005X5R1A225K050BC")
    (property "Manufacturer" "TDK")
    (property "Sheetfile" "power.kicad_sch")
    (property "Sheetname" "Power")
    (property "Val" "2u2")
    (property "Voltage" "")
    (property "ki_description" "SMD Multilayer Ceramic Capacitor, 2.2 µF, 10 V, 0402 [1005 Metric], ± 10%, X5R, C")
    (property "ki_keywords" "0402, SMT, CAPACITOR, PASSIVE, CERAMIC, MLCC")
    (attr smd)
    (fp_text reference "C35" (at -0.768 -4.509) (layer "B.SilkS")
        (effects (font (size 0.7 0.7) (thickness 0.15)) (justify left bottom mirror))
    )
    (fp_text value "C_2u2_0402" (at -1.022927 -2.155213) (layer "B.Fab")
        (effects (font (size 0.7 0.7) (thickness 0.15)) (justify left bottom mirror))
    )
    (fp_text user "${REFERENCE}" (at -0.939 -4.599) (layer "B.Fab") hide
        (effects (font (size 0.7 0.7) (thickness 0.15)) (justify left bottom mirror))
    )
    (fp_text user "License: Apache-2.0" (at -0.939 -5.799) (layer "B.Fab") hide
        (effects (font (size 0.7 0.7) (thickness 0.15)) (justify left bottom mirror))
    )
    (fp_text user "Author: Antmicro" (at -0.939 -3.399) (layer "B.Fab") hide
        (effects (font (size 0.7 0.7) (thickness 0.15)) (justify left bottom mirror))
    )
    (fp_rect (start -0.925 0.47) (end 0.925 -0.47)
      (stroke (width 0.05) (type default)) (fill none) (layer "B.CrtYd"))
    (fp_line (start -0.494 -0.248) (end -0.494 0.25)
      (stroke (width 0.15) (type solid)) (layer "B.Fab"))
    (fp_line (start -0.494 0.25) (end 0.504 0.25)
      (stroke (width 0.15) (type solid)) (layer "B.Fab"))
    (fp_line (start 0.504 -0.248) (end -0.494 -0.248)
      (stroke (width 0.15) (type solid)) (layer "B.Fab"))
    (fp_line (start 0.504 0.25) (end 0.504 -0.248)
      (stroke (width 0.15) (type solid)) (layer "B.Fab"))
    (pad "1" smd roundrect (at -0.48 0 180) (size 0.59 0.64) (layers "B.Cu" "B.Paste" "B.Mask") (roundrect_rratio 0.25)
      (net 102 "Net-(U3-LDO_1V8A)") (pintype "passive"))
    (pad "2" smd roundrect (at 0.48 0 180) (size 0.59 0.64) (layers "B.Cu" "B.Paste" "B.Mask") (roundrect_rratio 0.25)
      (net 1 "GND") (pintype "passive"))
  )
	(footprint "antmicro-footprints:C_0402_1005Metric" (layer "B.Cu")
    (at 136.75 78.875 180)
    (descr "Capacitor SMD 0402")
    (tags "capacitor SMD 0402")
    (property "Author" "Antmicro")
    (property "Dielectric" "")
    (property "License" "Apache-2.0")
    (property "MPN" "C1005X6S1A105K050BC")
    (property "Manufacturer" "TDK")
    (property "Sheetfile" "tb-power.kicad_sch")
    (property "Sheetname" "Thunderbolt Controller - Power")
    (property "Val" "1u")
    (property "Voltage" "")
    (property "ki_description" "SMD Multilayer Ceramic Capacitor, 1 µF, 10 V, 0402 [1005 Metric], ± 10%, X6S, C")
    (property "ki_keywords" "0402, SMT, CAPACITOR, PASSIVE, CERAMIC, MLCC")
    (attr smd)
    (fp_text reference "C77" (at -17.682 -7.993) (layer "B.SilkS")
        (effects (font (size 0.7 0.7) (thickness 0.15)) (justify left bottom mirror))
    )
    (fp_text value "C_1u_0402" (at -1.022927 -2.155213) (layer "B.Fab")
        (effects (font (size 0.7 0.7) (thickness 0.15)) (justify left bottom mirror))
    )
    (fp_text user "Author: Antmicro" (at -0.939 -3.399) (layer "B.Fab") hide
        (effects (font (size 0.7 0.7) (thickness 0.15)) (justify left bottom mirror))
    )
    (fp_text user "License: Apache-2.0" (at -0.939 -5.799) (layer "B.Fab") hide
        (effects (font (size 0.7 0.7) (thickness 0.15)) (justify left bottom mirror))
    )
    (fp_text user "${REFERENCE}" (at -0.939 -4.599) (layer "B.Fab") hide
        (effects (font (size 0.7 0.7) (thickness 0.15)) (justify left bottom mirror))
    )
    (fp_rect (start -0.925 0.47) (end 0.925 -0.47)
      (stroke (width 0.05) (type default)) (fill none) (layer "B.CrtYd"))
    (fp_line (start -0.494 -0.248) (end -0.494 0.25)
      (stroke (width 0.15) (type solid)) (layer "B.Fab"))
    (fp_line (start -0.494 0.25) (end 0.504 0.25)
      (stroke (width 0.15) (type solid)) (layer "B.Fab"))
    (fp_line (start 0.504 -0.248) (end -0.494 -0.248)
      (stroke (width 0.15) (type solid)) (layer "B.Fab"))
    (fp_line (start 0.504 0.25) (end 0.504 -0.248)
      (stroke (width 0.15) (type solid)) (layer "B.Fab"))
    (pad "1" smd roundrect (at -0.48 0 180) (size 0.59 0.64) (layers "B.Cu" "B.Paste" "B.Mask") (roundrect_rratio 0.25)
      (net 1 "GND") (pintype "passive"))
    (pad "2" smd roundrect (at 0.48 0 180) (size 0.59 0.64) (layers "B.Cu" "B.Paste" "B.Mask") (roundrect_rratio 0.25)
      (net 112 "Net-(U4A-VCC0P9_SVR_SENSE)") (pintype "passive"))
  )
	(footprint "antmicro-footprints:C_0402_1005Metric" (layer "B.Cu")
    (at 155.08 80.74 180)
    (descr "Capacitor SMD 0402")
    (tags "capacitor SMD 0402")
    (property "Author" "Antmicro")
    (property "Dielectric" "")
    (property "License" "Apache-2.0")
    (property "MPN" "CC0402KRX5R6BB224")
    (property "Manufacturer" "YAGEO")
    (property "Sheetfile" "tb.kicad_sch")
    (property "Sheetname" "TB Controller")
    (property "Val" "220n")
    (property "Voltage" "")
    (property "ki_description" "SMD Multilayer Ceramic Capacitor, 0.22 µF, 10 V, 0402 [1005 Metric], ± 10%, X5R, CC Series")
    (property "ki_keywords" "0402, SMT, CAPACITOR, PASSIVE, MLCC, CERAMIC")
    (attr smd)
    (fp_text reference "C102" (at 1.034 -0.431) (layer "B.SilkS")
        (effects (font (size 0.7 0.7) (thickness 0.15)) (justify left bottom mirror))
    )
    (fp_text value "C_220n_0402" (at -1.022927 -2.155213) (layer "B.Fab")
        (effects (font (size 0.7 0.7) (thickness 0.15)) (justify left bottom mirror))
    )
    (fp_text user "Author: Antmicro" (at -0.939 -3.399) (layer "B.Fab") hide
        (effects (font (size 0.7 0.7) (thickness 0.15)) (justify left bottom mirror))
    )
    (fp_text user "License: Apache-2.0" (at -0.939 -5.799) (layer "B.Fab") hide
        (effects (font (size 0.7 0.7) (thickness 0.15)) (justify left bottom mirror))
    )
    (fp_text user "${REFERENCE}" (at -0.939 -4.599) (layer "B.Fab") hide
        (effects (font (size 0.7 0.7) (thickness 0.15)) (justify left bottom mirror))
    )
    (fp_rect (start -0.925 0.47) (end 0.925 -0.47)
      (stroke (width 0.05) (type default)) (fill none) (layer "B.CrtYd"))
    (fp_line (start -0.494 -0.248) (end -0.494 0.25)
      (stroke (width 0.15) (type solid)) (layer "B.Fab"))
    (fp_line (start -0.494 0.25) (end 0.504 0.25)
      (stroke (width 0.15) (type solid)) (layer "B.Fab"))
    (fp_line (start 0.504 -0.248) (end -0.494 -0.248)
      (stroke (width 0.15) (type solid)) (layer "B.Fab"))
    (fp_line (start 0.504 0.25) (end 0.504 -0.248)
      (stroke (width 0.15) (type solid)) (layer "B.Fab"))
    (pad "1" smd roundrect (at -0.48 0 180) (size 0.59 0.64) (layers "B.Cu" "B.Paste" "B.Mask") (roundrect_rratio 0.25)
      (net 17 "TB_TX0_N") (pintype "passive"))
    (pad "2" smd roundrect (at 0.48 0 180) (size 0.59 0.64) (layers "B.Cu" "B.Paste" "B.Mask") (roundrect_rratio 0.25)
      (net 18 "/TB Controller/PA_TX0_N") (pintype "passive"))
  )
	(footprint "antmicro-footprints:R_0402_1005Metric" (layer "B.Cu")
    (at 113.675 83.68 180)
    (descr "Resistor SMD 0402")
    (tags "resistor SMD 0402")
    (property "Author" "Antmicro")
    (property "License" "Apache-2.0")
    (property "MPN" "CR0402-FX-1243GLF")
    (property "Manufacturer" "Bourns")
    (property "Sheetfile" "power.kicad_sch")
    (property "Sheetname" "Power")
    (property "Tolerance" "1%")
    (property "Val" "124k")
    (property "ki_description" "SMD Chip Resistor, 124 kohm, ± 1%, 100 mW, 0402 [1005 Metric], Thick Film, Precision")
    (property "ki_keywords" "0402, SMT, RESISTOR, PASSIVE")
    (attr smd)
    (fp_text reference "R28" (at -3.038 -0.394) (layer "B.SilkS")
        (effects (font (size 0.7 0.7) (thickness 0.15)) (justify left bottom mirror))
    )
    (fp_text value "R_124k_0402" (at -1.011843 -1.772047) (layer "B.Fab")
        (effects (font (size 0.7 0.7) (thickness 0.15)) (justify left bottom mirror))
    )
    (fp_text user "License: Apache-2.0" (at -0.95 -5.169) (layer "B.Fab") hide
        (effects (font (size 0.7 0.7) (thickness 0.15)) (justify left bottom mirror))
    )
    (fp_text user "${REFERENCE}" (at -0.95 -3.168) (layer "B.Fab") hide
        (effects (font (size 0.7 0.7) (thickness 0.15)) (justify left bottom mirror))
    )
    (fp_text user "Author: Antmicro" (at -0.95 -4.169) (layer "B.Fab") hide
        (effects (font (size 0.7 0.7) (thickness 0.15)) (justify left bottom mirror))
    )
    (fp_rect (start -0.925 0.47) (end 0.925 -0.47)
      (stroke (width 0.05) (type default)) (fill none) (layer "B.CrtYd"))
    (fp_rect (start -0.5 0.25) (end 0.5 -0.25)
      (stroke (width 0.15) (type solid)) (fill none) (layer "B.Fab"))
    (pad "1" smd roundrect (at -0.48 0 180) (size 0.59 0.64) (layers "B.Cu" "B.Paste" "B.Mask") (roundrect_rratio 0.25)
      (net 1 "GND") (pintype "passive"))
    (pad "2" smd roundrect (at 0.48 0 180) (size 0.59 0.64) (layers "B.Cu" "B.Paste" "B.Mask") (roundrect_rratio 0.25)
      (net 161 "Net-(U1-RT)") (pintype "passive"))
  )
)
